# T6G (Grand Teton) — schematic netlist excerpt (pin names and nets, part order shuffled) for the footprints in the layout excerpt that follows; sources: Cadence DE-HDL packaged netlist, KiCad conversion of 04192023_DAF0TMB3IC0_F0TG_MB_C_brd_V02_OCP.brd

PC2193  Q_CAP  0.047UF 25V 10% X7R  pkg C0402  page 262 : A = HSC_IMON ; B = AGND_HSC
PL8065  Q_INDUCTOR  4.7UH IND  pkg SMLF  page 189 : \1\ = SW_P5V_AUX_SW ; \2\ = P5V_AUX
R4209  Q_RES  200K 1% EMPTY  pkg 0402LF  page 235 : A = P3V3_AUX ; B = FM_THERMAL_ALERT_N

(kicad_pcb
	(version 20260206)
	(generator "pcbnew")
	(generator_version "10.0")
	(general
		(thickness 1.6)
		(legacy_teardrops no)
	)
	(paper "A4")
	(title_block
		(title "04192023_DAF0TMB3IC0_F0TG_MB_C_brd_V02_OCP.brd")
		(comment 1 "Grand Teton / footprints 4232-4234 of 8354")
	)
	(layers
		(0 "F.Cu" signal "TOP")
		(4 "In1.Cu" signal "GND")
		(6 "In2.Cu" signal "IN1")
		(8 "In3.Cu" signal "GND1")
		(10 "In4.Cu" signal "IN2")
		(12 "In5.Cu" signal "GND2")
		(14 "In6.Cu" signal "IN3")
		(16 "In7.Cu" signal "GND3")
		(18 "In8.Cu" signal "VCC")
		(20 "In9.Cu" signal "VCC1")
		(22 "In10.Cu" signal "GND4")
		(24 "In11.Cu" signal "IN4")
		(26 "In12.Cu" signal "GND5")
		(28 "In13.Cu" signal "IN5")
		(30 "In14.Cu" signal "GND6")
		(32 "In15.Cu" signal "IN6")
		(34 "In16.Cu" signal "GND7")
		(2 "B.Cu" signal "BOTTOM")
		(9 "F.Adhes" user "F.Adhesive")
		(11 "B.Adhes" user "B.Adhesive")
		(13 "F.Paste" user "Package Geometry/Pastemask Top")
		(15 "B.Paste" user "Package Geometry/Pastemask Bottom")
		(5 "F.SilkS" user "Ref Des/Silkscreen Top")
		(7 "B.SilkS" user "Ref Des/Silkscreen Bottom")
		(1 "F.Mask" user "Board Geometry/Soldermask Top")
		(3 "B.Mask" user "Board Geometry/Soldermask Bottom")
		(17 "Dwgs.User" user "User.Drawings")
		(19 "Cmts.User" user "User.Comments")
		(21 "Eco1.User" user "User.Eco1")
		(23 "Eco2.User" user "User.Eco2")
		(25 "Edge.Cuts" user "Board Geometry/Outline")
		(27 "Margin" user)
		(31 "F.CrtYd" user "Package Geometry/Place Bound Top")
		(29 "B.CrtYd" user "Package Geometry/Place Bound Bottom")
		(35 "F.Fab" user "Ref Des/Assembly Top")
		(33 "B.Fab" user "Ref Des/Assembly Bottom")
	)
	(footprint ""
		(layer "F.Cu")
		(at 178.71694 -397.388842 180)
		(property "Reference" "PC2193"
			(at 0 0 180)
			(layer "F.SilkS")
			(hide yes)
			(effects
				(font
					(size 1.27 1.27)
				)
			)
		)
		(property "Value" ""
			(at 0 0 180)
			(layer "F.Fab")
			(effects
				(font
					(size 1.27 1.27)
				)
			)
		)
		(duplicate_pad_numbers_are_jumpers no)
		(fp_line
			(start 0.7874 0.4064)
			(end -0.7874 0.4064)
			(stroke
				(width 0.1524)
				(type default)
			)
			(layer "F.SilkS")
		)
		(fp_line
			(start 0.7874 -0.4064)
			(end 0.7874 0.4064)
			(stroke
				(width 0.1524)
				(type default)
			)
			(layer "F.SilkS")
		)
		(fp_line
			(start -0.7874 0.4064)
			(end -0.7874 -0.4064)
			(stroke
				(width 0.1524)
				(type default)
			)
			(layer "F.SilkS")
		)
		(fp_line
			(start -0.7874 -0.4064)
			(end 0.7874 -0.4064)
			(stroke
				(width 0.1524)
				(type default)
			)
			(layer "F.SilkS")
		)
		(fp_line
			(start 0.67945 0.3048)
			(end 0.120396 0.3048)
			(stroke
				(width 0.1)
				(type default)
			)
			(layer "F.Fab")
		)
		(fp_line
			(start 0.67945 -0.3048)
			(end 0.67945 0.3048)
			(stroke
				(width 0.1)
				(type default)
			)
			(layer "F.Fab")
		)
		(fp_line
			(start 0.12065 -0.2794)
			(end 0.12065 -0.3048)
			(stroke
				(width 0.1)
				(type default)
			)
			(layer "F.Fab")
		)
		(fp_line
			(start 0.12065 -0.3048)
			(end 0.67945 -0.3048)
			(stroke
				(width 0.1)
				(type default)
			)
			(layer "F.Fab")
		)
		(fp_line
			(start 0.120396 0.3048)
			(end 0.120396 0.2794)
			(stroke
				(width 0.1)
				(type default)
			)
			(layer "F.Fab")
		)
		(fp_line
			(start 0.120396 0.2794)
			(end -0.12065 0.2794)
			(stroke
				(width 0.1)
				(type default)
			)
			(layer "F.Fab")
		)
		(fp_line
			(start -0.12065 0.3048)
			(end -0.67945 0.3048)
			(stroke
				(width 0.1)
				(type default)
			)
			(layer "F.Fab")
		)
		(fp_line
			(start -0.12065 0.2794)
			(end -0.12065 0.3048)
			(stroke
				(width 0.1)
				(type default)
			)
			(layer "F.Fab")
		)
		(fp_line
			(start -0.12065 -0.2794)
			(end 0.12065 -0.2794)
			(stroke
				(width 0.1)
				(type default)
			)
			(layer "F.Fab")
		)
		(fp_line
			(start -0.12065 -0.305054)
			(end -0.12065 -0.2794)
			(stroke
				(width 0.1)
				(type default)
			)
			(layer "F.Fab")
		)
		(fp_line
			(start -0.67945 0.3048)
			(end -0.67945 -0.305054)
			(stroke
				(width 0.1)
				(type default)
			)
			(layer "F.Fab")
		)
		(fp_line
			(start -0.67945 -0.305054)
			(end -0.12065 -0.305054)
			(stroke
				(width 0.1)
				(type default)
			)
			(layer "F.Fab")
		)
		(pad "1" smd circle
			(at -0.40005 0 180)
			(size 0 0)
			(layers "F.Cu" "F.Mask" "F.Paste")
			(net "HSC_IMON")
		)
		(pad "2" smd circle
			(at 0.40005 0 180)
			(size 0 0)
			(layers "F.Cu" "F.Mask" "F.Paste")
			(net "AGND_HSC")
		)
	)
	(footprint ""
		(layer "F.Cu")
		(at 286.571182 -13.373354)
		(property "Reference" "R4209"
			(at 0 0 0)
			(layer "F.SilkS")
			(hide yes)
			(effects
				(font
					(size 1.27 1.27)
				)
			)
		)
		(property "Value" ""
			(at 0 0 0)
			(layer "F.Fab")
			(effects
				(font
					(size 1.27 1.27)
				)
			)
		)
		(duplicate_pad_numbers_are_jumpers no)
		(fp_line
			(start -0.7874 -0.4064)
			(end 0.7874 -0.4064)
			(stroke
				(width 0.1524)
				(type default)
			)
			(layer "F.SilkS")
		)
		(fp_line
			(start -0.7874 0.4064)
			(end -0.7874 -0.4064)
			(stroke
				(width 0.1524)
				(type default)
			)
			(layer "F.SilkS")
		)
		(fp_line
			(start 0.7874 -0.4064)
			(end 0.7874 0.4064)
			(stroke
				(width 0.1524)
				(type default)
			)
			(layer "F.SilkS")
		)
		(fp_line
			(start 0.7874 0.4064)
			(end -0.7874 0.4064)
			(stroke
				(width 0.1524)
				(type default)
			)
			(layer "F.SilkS")
		)
		(fp_line
			(start -0.67945 -0.305054)
			(end -0.12065 -0.305054)
			(stroke
				(width 0.1)
				(type default)
			)
			(layer "F.Fab")
		)
		(fp_line
			(start -0.67945 0.3048)
			(end -0.67945 -0.305054)
			(stroke
				(width 0.1)
				(type default)
			)
			(layer "F.Fab")
		)
		(fp_line
			(start -0.12065 -0.305054)
			(end -0.12065 -0.2794)
			(stroke
				(width 0.1)
				(type default)
			)
			(layer "F.Fab")
		)
		(fp_line
			(start -0.12065 -0.2794)
			(end 0.12065 -0.2794)
			(stroke
				(width 0.1)
				(type default)
			)
			(layer "F.Fab")
		)
		(fp_line
			(start -0.12065 0.2794)
			(end -0.12065 0.3048)
			(stroke
				(width 0.1)
				(type default)
			)
			(layer "F.Fab")
		)
		(fp_line
			(start -0.12065 0.3048)
			(end -0.67945 0.3048)
			(stroke
				(width 0.1)
				(type default)
			)
			(layer "F.Fab")
		)
		(fp_line
			(start 0.120396 0.2794)
			(end -0.12065 0.2794)
			(stroke
				(width 0.1)
				(type default)
			)
			(layer "F.Fab")
		)
		(fp_line
			(start 0.120396 0.3048)
			(end 0.120396 0.2794)
			(stroke
				(width 0.1)
				(type default)
			)
			(layer "F.Fab")
		)
		(fp_line
			(start 0.12065 -0.3048)
			(end 0.67945 -0.3048)
			(stroke
				(width 0.1)
				(type default)
			)
			(layer "F.Fab")
		)
		(fp_line
			(start 0.12065 -0.2794)
			(end 0.12065 -0.3048)
			(stroke
				(width 0.1)
				(type default)
			)
			(layer "F.Fab")
		)
		(fp_line
			(start 0.67945 -0.3048)
			(end 0.67945 0.3048)
			(stroke
				(width 0.1)
				(type default)
			)
			(layer "F.Fab")
		)
		(fp_line
			(start 0.67945 0.3048)
			(end 0.120396 0.3048)
			(stroke
				(width 0.1)
				(type default)
			)
			(layer "F.Fab")
		)
		(pad "1" smd circle
			(at -0.40005 0)
			(size 0 0)
			(layers "F.Cu" "F.Mask" "F.Paste")
			(net "P3V3_AUX")
		)
		(pad "2" smd circle
			(at 0.40005 0)
			(size 0 0)
			(layers "F.Cu" "F.Mask" "F.Paste")
			(net "FM_THERMAL_ALERT_N")
		)
	)
	(footprint ""
		(layer "F.Cu")
		(at 413.303466 -150.858982 90)
		(property "Reference" "PL8065"
			(at 1.033018 -5.987796 90)
			(unlocked yes)
			(layer "F.SilkS")
			(effects
				(font
					(size 0.7874 0.5842)
					(thickness 0.1524)
				)
				(justify left)
			)
		)
		(property "Value" ""
			(at 0 0 90)
			(layer "F.Fab")
			(effects
				(font
					(size 1.27 1.27)
				)
			)
		)
		(duplicate_pad_numbers_are_jumpers no)
		(fp_line
			(start 5.588 -5.150104)
			(end -5.588 -5.150104)
			(stroke
				(width 0.1524)
				(type default)
			)
			(layer "F.SilkS")
		)
		(fp_line
			(start -5.588 -5.150104)
			(end -5.588 -1.8542)
			(stroke
				(width 0.1524)
				(type default)
			)
			(layer "F.SilkS")
		)
		(fp_line
			(start 5.588 -1.8288)
			(end 5.588 -5.150104)
			(stroke
				(width 0.1524)
				(type default)
			)
			(layer "F.SilkS")
		)
		(fp_line
			(start -5.588 1.8288)
			(end -5.588 5.150104)
			(stroke
				(width 0.1524)
				(type default)
			)
			(layer "F.SilkS")
		)
		(fp_line
			(start 5.588 5.150104)
			(end 5.588 1.8034)
			(stroke
				(width 0.1524)
				(type default)
			)
			(layer "F.SilkS")
		)
		(fp_line
			(start -5.588 5.150104)
			(end 5.588 5.150104)
			(stroke
				(width 0.1524)
				(type default)
			)
			(layer "F.SilkS")
		)
		(fp_line
			(start 5.599938 -5.150104)
			(end 5.599938 5.150104)
			(stroke
				(width 0.1)
				(type default)
			)
			(layer "F.Fab")
		)
		(fp_line
			(start -5.599938 -5.150104)
			(end 5.599938 -5.150104)
			(stroke
				(width 0.1)
				(type default)
			)
			(layer "F.Fab")
		)
		(fp_line
			(start 5.599938 5.150104)
			(end -5.599938 5.150104)
			(stroke
				(width 0.1)
				(type default)
			)
			(layer "F.Fab")
		)
		(fp_line
			(start -5.599938 5.150104)
			(end -5.599938 -5.150104)
			(stroke
				(width 0.1)
				(type default)
			)
			(layer "F.Fab")
		)
		(pad "1" smd rect
			(at -4.338828 0 90)
			(size 3.302 3.302)
			(layers "F.Cu" "F.Mask" "F.Paste")
			(net "SW_P5V_AUX_SW")
		)
		(pad "2" smd rect
			(at 4.338828 0 90)
			(size 3.302 3.302)
			(layers "F.Cu" "F.Mask" "F.Paste")
			(net "P5V_AUX")
		)
	)
)
